(kicad_pcb
	(version 20260206)
	(generator "pcbnew")
	(generator_version "10.0")
	(general
		(thickness 1.6)
		(legacy_teardrops no)
	)
	(paper "A4")
	(title_block
		(title "01162023_DA0F0TEBIF0_F0T_Expander_BD_F_brd_V02_OCP.brd")
		(comment 1 "Grand Teton / footprints 904-910 of 9728")
	)
	(layers
		(0 "F.Cu" signal "TOP")
		(4 "In1.Cu" signal "GND")
		(6 "In2.Cu" signal "VCC")
		(8 "In3.Cu" signal "VCC1")
		(10 "In4.Cu" signal "GND1")
		(12 "In5.Cu" signal "IN1")
		(14 "In6.Cu" signal "GND2")
		(16 "In7.Cu" signal "IN2")
		(18 "In8.Cu" signal "GND3")
		(20 "In9.Cu" signal "IN3")
		(22 "In10.Cu" signal "GND4")
		(24 "In11.Cu" signal "IN4")
		(26 "In12.Cu" signal "GND5")
		(28 "In13.Cu" signal "IN5")
		(30 "In14.Cu" signal "GND6")
		(32 "In15.Cu" signal "IN6")
		(34 "In16.Cu" signal "GND7")
		(2 "B.Cu" signal "BOTTOM")
		(9 "F.Adhes" user "F.Adhesive")
		(11 "B.Adhes" user "B.Adhesive")
		(13 "F.Paste" user "Package Geometry/Pastemask Top")
		(15 "B.Paste" user "Package Geometry/Pastemask Bottom")
		(5 "F.SilkS" user "Ref Des/Silkscreen Top")
		(7 "B.SilkS" user "Ref Des/Silkscreen Bottom")
		(1 "F.Mask" user "Board Geometry/Soldermask Top")
		(3 "B.Mask" user "Board Geometry/Soldermask Bottom")
		(17 "Dwgs.User" user "User.Drawings")
		(19 "Cmts.User" user "User.Comments")
		(21 "Eco1.User" user "User.Eco1")
		(23 "Eco2.User" user "User.Eco2")
		(25 "Edge.Cuts" user "Board Geometry/Outline")
		(27 "Margin" user)
		(31 "F.CrtYd" user "Package Geometry/Place Bound Top")
		(29 "B.CrtYd" user "Package Geometry/Place Bound Bottom")
		(35 "F.Fab" user "Ref Des/Assembly Top")
		(33 "B.Fab" user "Ref Des/Assembly Bottom")
	)
	(footprint ""
		(layer "F.Cu")
		(at 264.611358 -299.645832 -90)
		(property "Reference" "R4579"
			(at 0 0 270)
			(layer "F.SilkS")
			(hide yes)
			(effects
				(font
					(size 1.27 1.27)
				)
			)
		)
		(property "Value" ""
			(at 0 0 270)
			(layer "F.Fab")
			(effects
				(font
					(size 1.27 1.27)
				)
			)
		)
		(duplicate_pad_numbers_are_jumpers no)
		(fp_line
			(start -0.7874 0.4064)
			(end -0.7874 -0.4064)
			(stroke
				(width 0.1524)
				(type default)
			)
			(layer "F.SilkS")
		)
		(fp_line
			(start 0.7874 0.4064)
			(end -0.7874 0.4064)
			(stroke
				(width 0.1524)
				(type default)
			)
			(layer "F.SilkS")
		)
		(fp_line
			(start -0.7874 -0.4064)
			(end 0.7874 -0.4064)
			(stroke
				(width 0.1524)
				(type default)
			)
			(layer "F.SilkS")
		)
		(fp_line
			(start 0.7874 -0.4064)
			(end 0.7874 0.4064)
			(stroke
				(width 0.1524)
				(type default)
			)
			(layer "F.SilkS")
		)
		(fp_line
			(start -0.67945 0.3048)
			(end -0.67945 -0.305054)
			(stroke
				(width 0.1)
				(type default)
			)
			(layer "F.Fab")
		)
		(fp_line
			(start -0.12065 0.3048)
			(end -0.67945 0.3048)
			(stroke
				(width 0.1)
				(type default)
			)
			(layer "F.Fab")
		)
		(fp_line
			(start 0.120396 0.3048)
			(end 0.120396 0.2794)
			(stroke
				(width 0.1)
				(type default)
			)
			(layer "F.Fab")
		)
		(fp_line
			(start 0.67945 0.3048)
			(end 0.120396 0.3048)
			(stroke
				(width 0.1)
				(type default)
			)
			(layer "F.Fab")
		)
		(fp_line
			(start -0.12065 0.2794)
			(end -0.12065 0.3048)
			(stroke
				(width 0.1)
				(type default)
			)
			(layer "F.Fab")
		)
		(fp_line
			(start 0.120396 0.2794)
			(end -0.12065 0.2794)
			(stroke
				(width 0.1)
				(type default)
			)
			(layer "F.Fab")
		)
		(fp_line
			(start -0.12065 -0.2794)
			(end 0.12065 -0.2794)
			(stroke
				(width 0.1)
				(type default)
			)
			(layer "F.Fab")
		)
		(fp_line
			(start 0.12065 -0.2794)
			(end 0.12065 -0.3048)
			(stroke
				(width 0.1)
				(type default)
			)
			(layer "F.Fab")
		)
		(fp_line
			(start 0.12065 -0.3048)
			(end 0.67945 -0.3048)
			(stroke
				(width 0.1)
				(type default)
			)
			(layer "F.Fab")
		)
		(fp_line
			(start 0.67945 -0.3048)
			(end 0.67945 0.3048)
			(stroke
				(width 0.1)
				(type default)
			)
			(layer "F.Fab")
		)
		(fp_line
			(start -0.67945 -0.305054)
			(end -0.12065 -0.305054)
			(stroke
				(width 0.1)
				(type default)
			)
			(layer "F.Fab")
		)
		(fp_line
			(start -0.12065 -0.305054)
			(end -0.12065 -0.2794)
			(stroke
				(width 0.1)
				(type default)
			)
			(layer "F.Fab")
		)
		(pad "1" smd circle
			(at -0.40005 0 270)
			(size 0 0)
			(layers "F.Cu" "F.Mask" "F.Paste")
			(net "PCEPLL1_VDDA18_PEX2")
		)
		(pad "2" smd circle
			(at 0.40005 0 270)
			(size 0 0)
			(layers "F.Cu" "F.Mask" "F.Paste")
			(net "PCEPLL1_VDDA18_PEX2_R")
		)
	)
	(footprint ""
		(layer "F.Cu")
		(at 348.982792 -240.691162 -90)
		(property "Reference" "R3549"
			(at 0 0 270)
			(layer "F.SilkS")
			(hide yes)
			(effects
				(font
					(size 1.27 1.27)
				)
			)
		)
		(property "Value" ""
			(at 0 0 270)
			(layer "F.Fab")
			(effects
				(font
					(size 1.27 1.27)
				)
			)
		)
		(duplicate_pad_numbers_are_jumpers no)
		(fp_line
			(start -0.7874 0.4064)
			(end -0.7874 -0.4064)
			(stroke
				(width 0.1524)
				(type default)
			)
			(layer "F.SilkS")
		)
		(fp_line
			(start 0.7874 0.4064)
			(end -0.7874 0.4064)
			(stroke
				(width 0.1524)
				(type default)
			)
			(layer "F.SilkS")
		)
		(fp_line
			(start -0.7874 -0.4064)
			(end 0.7874 -0.4064)
			(stroke
				(width 0.1524)
				(type default)
			)
			(layer "F.SilkS")
		)
		(fp_line
			(start 0.7874 -0.4064)
			(end 0.7874 0.4064)
			(stroke
				(width 0.1524)
				(type default)
			)
			(layer "F.SilkS")
		)
		(fp_line
			(start -0.67945 0.3048)
			(end -0.67945 -0.305054)
			(stroke
				(width 0.1)
				(type default)
			)
			(layer "F.Fab")
		)
		(fp_line
			(start -0.12065 0.3048)
			(end -0.67945 0.3048)
			(stroke
				(width 0.1)
				(type default)
			)
			(layer "F.Fab")
		)
		(fp_line
			(start 0.120396 0.3048)
			(end 0.120396 0.2794)
			(stroke
				(width 0.1)
				(type default)
			)
			(layer "F.Fab")
		)
		(fp_line
			(start 0.67945 0.3048)
			(end 0.120396 0.3048)
			(stroke
				(width 0.1)
				(type default)
			)
			(layer "F.Fab")
		)
		(fp_line
			(start -0.12065 0.2794)
			(end -0.12065 0.3048)
			(stroke
				(width 0.1)
				(type default)
			)
			(layer "F.Fab")
		)
		(fp_line
			(start 0.120396 0.2794)
			(end -0.12065 0.2794)
			(stroke
				(width 0.1)
				(type default)
			)
			(layer "F.Fab")
		)
		(fp_line
			(start -0.12065 -0.2794)
			(end 0.12065 -0.2794)
			(stroke
				(width 0.1)
				(type default)
			)
			(layer "F.Fab")
		)
		(fp_line
			(start 0.12065 -0.2794)
			(end 0.12065 -0.3048)
			(stroke
				(width 0.1)
				(type default)
			)
			(layer "F.Fab")
		)
		(fp_line
			(start 0.12065 -0.3048)
			(end 0.67945 -0.3048)
			(stroke
				(width 0.1)
				(type default)
			)
			(layer "F.Fab")
		)
		(fp_line
			(start 0.67945 -0.3048)
			(end 0.67945 0.3048)
			(stroke
				(width 0.1)
				(type default)
			)
			(layer "F.Fab")
		)
		(fp_line
			(start -0.67945 -0.305054)
			(end -0.12065 -0.305054)
			(stroke
				(width 0.1)
				(type default)
			)
			(layer "F.Fab")
		)
		(fp_line
			(start -0.12065 -0.305054)
			(end -0.12065 -0.2794)
			(stroke
				(width 0.1)
				(type default)
			)
			(layer "F.Fab")
		)
		(pad "1" smd circle
			(at -0.40005 0 270)
			(size 0 0)
			(layers "F.Cu" "F.Mask" "F.Paste")
			(net "SSD4_PWR_EN_R")
		)
		(pad "2" smd circle
			(at 0.40005 0 270)
			(size 0 0)
			(layers "F.Cu" "F.Mask" "F.Paste")
			(net "SSD4_PWR_EN")
		)
	)
	(footprint ""
		(layer "F.Cu")
		(at 355.854 -177.546)
		(property "Reference" "R4743"
			(at 0 0 0)
			(layer "F.SilkS")
			(hide yes)
			(effects
				(font
					(size 1.27 1.27)
				)
			)
		)
		(property "Value" ""
			(at 0 0 0)
			(layer "F.Fab")
			(effects
				(font
					(size 1.27 1.27)
				)
			)
		)
		(duplicate_pad_numbers_are_jumpers no)
		(fp_line
			(start -0.7874 -0.4064)
			(end 0.7874 -0.4064)
			(stroke
				(width 0.1524)
				(type default)
			)
			(layer "F.SilkS")
		)
		(fp_line
			(start -0.7874 0.4064)
			(end -0.7874 -0.4064)
			(stroke
				(width 0.1524)
				(type default)
			)
			(layer "F.SilkS")
		)
		(fp_line
			(start 0.7874 -0.4064)
			(end 0.7874 0.4064)
			(stroke
				(width 0.1524)
				(type default)
			)
			(layer "F.SilkS")
		)
		(fp_line
			(start 0.7874 0.4064)
			(end -0.7874 0.4064)
			(stroke
				(width 0.1524)
				(type default)
			)
			(layer "F.SilkS")
		)
		(fp_line
			(start -0.67945 -0.305054)
			(end -0.12065 -0.305054)
			(stroke
				(width 0.1)
				(type default)
			)
			(layer "F.Fab")
		)
		(fp_line
			(start -0.67945 0.3048)
			(end -0.67945 -0.305054)
			(stroke
				(width 0.1)
				(type default)
			)
			(layer "F.Fab")
		)
		(fp_line
			(start -0.12065 -0.305054)
			(end -0.12065 -0.2794)
			(stroke
				(width 0.1)
				(type default)
			)
			(layer "F.Fab")
		)
		(fp_line
			(start -0.12065 -0.2794)
			(end 0.12065 -0.2794)
			(stroke
				(width 0.1)
				(type default)
			)
			(layer "F.Fab")
		)
		(fp_line
			(start -0.12065 0.2794)
			(end -0.12065 0.3048)
			(stroke
				(width 0.1)
				(type default)
			)
			(layer "F.Fab")
		)
		(fp_line
			(start -0.12065 0.3048)
			(end -0.67945 0.3048)
			(stroke
				(width 0.1)
				(type default)
			)
			(layer "F.Fab")
		)
		(fp_line
			(start 0.120396 0.2794)
			(end -0.12065 0.2794)
			(stroke
				(width 0.1)
				(type default)
			)
			(layer "F.Fab")
		)
		(fp_line
			(start 0.120396 0.3048)
			(end 0.120396 0.2794)
			(stroke
				(width 0.1)
				(type default)
			)
			(layer "F.Fab")
		)
		(fp_line
			(start 0.12065 -0.3048)
			(end 0.67945 -0.3048)
			(stroke
				(width 0.1)
				(type default)
			)
			(layer "F.Fab")
		)
		(fp_line
			(start 0.12065 -0.2794)
			(end 0.12065 -0.3048)
			(stroke
				(width 0.1)
				(type default)
			)
			(layer "F.Fab")
		)
		(fp_line
			(start 0.67945 -0.3048)
			(end 0.67945 0.3048)
			(stroke
				(width 0.1)
				(type default)
			)
			(layer "F.Fab")
		)
		(fp_line
			(start 0.67945 0.3048)
			(end 0.120396 0.3048)
			(stroke
				(width 0.1)
				(type default)
			)
			(layer "F.Fab")
		)
		(pad "1" smd circle
			(at -0.40005 0)
			(size 0 0)
			(layers "F.Cu" "F.Mask" "F.Paste")
			(net "NIC4_PEX_PWR_EN_R")
		)
		(pad "2" smd circle
			(at 0.40005 0)
			(size 0 0)
			(layers "F.Cu" "F.Mask" "F.Paste")
			(net "GND")
		)
	)
	(footprint ""
		(layer "F.Cu")
		(at 439.93435 -310.478932 -45)
		(property "Reference" "R3946"
			(at 0 0 315)
			(layer "F.SilkS")
			(hide yes)
			(effects
				(font
					(size 1.27 1.27)
				)
			)
		)
		(property "Value" ""
			(at 0 0 315)
			(layer "F.Fab")
			(effects
				(font
					(size 1.27 1.27)
				)
			)
		)
		(duplicate_pad_numbers_are_jumpers no)
		(fp_line
			(start -0.787389 0.406267)
			(end -0.787389 -0.406267)
			(stroke
				(width 0.1524)
				(type default)
			)
			(layer "F.SilkS")
		)
		(fp_line
			(start -0.787389 -0.406267)
			(end 0.787389 -0.406267)
			(stroke
				(width 0.1524)
				(type default)
			)
			(layer "F.SilkS")
		)
		(fp_line
			(start 0.787389 0.406267)
			(end -0.787389 0.406267)
			(stroke
				(width 0.1524)
				(type default)
			)
			(layer "F.SilkS")
		)
		(fp_line
			(start 0.787389 -0.406267)
			(end 0.787389 0.406267)
			(stroke
				(width 0.1524)
				(type default)
			)
			(layer "F.SilkS")
		)
		(fp_line
			(start -0.679446 0.30479)
			(end -0.679446 -0.305149)
			(stroke
				(width 0.1)
				(type default)
			)
			(layer "F.Fab")
		)
		(fp_line
			(start -0.120515 0.30479)
			(end -0.679446 0.30479)
			(stroke
				(width 0.1)
				(type default)
			)
			(layer "F.Fab")
		)
		(fp_line
			(start -0.120695 0.279466)
			(end -0.120515 0.30479)
			(stroke
				(width 0.1)
				(type default)
			)
			(layer "F.Fab")
		)
		(fp_line
			(start -0.679446 -0.305149)
			(end -0.120695 -0.304969)
			(stroke
				(width 0.1)
				(type default)
			)
			(layer "F.Fab")
		)
		(fp_line
			(start 0.120515 0.30479)
			(end 0.120335 0.279466)
			(stroke
				(width 0.1)
				(type default)
			)
			(layer "F.Fab")
		)
		(fp_line
			(start 0.120335 0.279466)
			(end -0.120695 0.279466)
			(stroke
				(width 0.1)
				(type default)
			)
			(layer "F.Fab")
		)
		(fp_line
			(start -0.120695 -0.279466)
			(end 0.120695 -0.279466)
			(stroke
				(width 0.1)
				(type default)
			)
			(layer "F.Fab")
		)
		(fp_line
			(start -0.120695 -0.304969)
			(end -0.120695 -0.279466)
			(stroke
				(width 0.1)
				(type default)
			)
			(layer "F.Fab")
		)
		(fp_line
			(start 0.679446 0.30479)
			(end 0.120515 0.30479)
			(stroke
				(width 0.1)
				(type default)
			)
			(layer "F.Fab")
		)
		(fp_line
			(start 0.120695 -0.279466)
			(end 0.120515 -0.30479)
			(stroke
				(width 0.1)
				(type default)
			)
			(layer "F.Fab")
		)
		(fp_line
			(start 0.120515 -0.30479)
			(end 0.679446 -0.30479)
			(stroke
				(width 0.1)
				(type default)
			)
			(layer "F.Fab")
		)
		(fp_line
			(start 0.679446 -0.30479)
			(end 0.679446 0.30479)
			(stroke
				(width 0.1)
				(type default)
			)
			(layer "F.Fab")
		)
		(pad "1" smd circle
			(at -0.40005 0 315)
			(size 0 0)
			(layers "F.Cu" "F.Mask" "F.Paste")
			(net "PU_PEX3_SIO_BLINK")
		)
		(pad "2" smd circle
			(at 0.40005 0 315)
			(size 0 0)
			(layers "F.Cu" "F.Mask" "F.Paste")
			(net "P1V8_PEX")
		)
	)
	(footprint ""
		(layer "F.Cu")
		(at 376.138694 -311.156604 -90)
		(property "Reference" "R1399"
			(at 0 0 270)
			(layer "F.SilkS")
			(hide yes)
			(effects
				(font
					(size 1.27 1.27)
				)
			)
		)
		(property "Value" ""
			(at 0 0 270)
			(layer "F.Fab")
			(effects
				(font
					(size 1.27 1.27)
				)
			)
		)
		(duplicate_pad_numbers_are_jumpers no)
		(fp_line
			(start -0.7874 0.4064)
			(end -0.7874 -0.4064)
			(stroke
				(width 0.1524)
				(type default)
			)
			(layer "F.SilkS")
		)
		(fp_line
			(start 0.7874 0.4064)
			(end -0.7874 0.4064)
			(stroke
				(width 0.1524)
				(type default)
			)
			(layer "F.SilkS")
		)
		(fp_line
			(start -0.7874 -0.4064)
			(end 0.7874 -0.4064)
			(stroke
				(width 0.1524)
				(type default)
			)
			(layer "F.SilkS")
		)
		(fp_line
			(start 0.7874 -0.4064)
			(end 0.7874 0.4064)
			(stroke
				(width 0.1524)
				(type default)
			)
			(layer "F.SilkS")
		)
		(fp_line
			(start -0.67945 0.3048)
			(end -0.67945 -0.305054)
			(stroke
				(width 0.1)
				(type default)
			)
			(layer "F.Fab")
		)
		(fp_line
			(start -0.12065 0.3048)
			(end -0.67945 0.3048)
			(stroke
				(width 0.1)
				(type default)
			)
			(layer "F.Fab")
		)
		(fp_line
			(start 0.120396 0.3048)
			(end 0.120396 0.2794)
			(stroke
				(width 0.1)
				(type default)
			)
			(layer "F.Fab")
		)
		(fp_line
			(start 0.67945 0.3048)
			(end 0.120396 0.3048)
			(stroke
				(width 0.1)
				(type default)
			)
			(layer "F.Fab")
		)
		(fp_line
			(start -0.12065 0.2794)
			(end -0.12065 0.3048)
			(stroke
				(width 0.1)
				(type default)
			)
			(layer "F.Fab")
		)
		(fp_line
			(start 0.120396 0.2794)
			(end -0.12065 0.2794)
			(stroke
				(width 0.1)
				(type default)
			)
			(layer "F.Fab")
		)
		(fp_line
			(start -0.12065 -0.2794)
			(end 0.12065 -0.2794)
			(stroke
				(width 0.1)
				(type default)
			)
			(layer "F.Fab")
		)
		(fp_line
			(start 0.12065 -0.2794)
			(end 0.12065 -0.3048)
			(stroke
				(width 0.1)
				(type default)
			)
			(layer "F.Fab")
		)
		(fp_line
			(start 0.12065 -0.3048)
			(end 0.67945 -0.3048)
			(stroke
				(width 0.1)
				(type default)
			)
			(layer "F.Fab")
		)
		(fp_line
			(start 0.67945 -0.3048)
			(end 0.67945 0.3048)
			(stroke
				(width 0.1)
				(type default)
			)
			(layer "F.Fab")
		)
		(fp_line
			(start -0.67945 -0.305054)
			(end -0.12065 -0.305054)
			(stroke
				(width 0.1)
				(type default)
			)
			(layer "F.Fab")
		)
		(fp_line
			(start -0.12065 -0.305054)
			(end -0.12065 -0.2794)
			(stroke
				(width 0.1)
				(type default)
			)
			(layer "F.Fab")
		)
		(pad "1" smd circle
			(at -0.40005 0 270)
			(size 0 0)
			(layers "F.Cu" "F.Mask" "F.Paste")
			(net "PEX3_DBG_SEL1")
		)
		(pad "2" smd circle
			(at 0.40005 0 270)
			(size 0 0)
			(layers "F.Cu" "F.Mask" "F.Paste")
			(net "P1V8_PEX")
		)
	)
	(footprint ""
		(layer "F.Cu")
		(at 45.093128 -350.098614 90)
		(property "Reference" "C168"
			(at 0 0 90)
			(layer "F.SilkS")
			(hide yes)
			(effects
				(font
					(size 1.27 1.27)
				)
			)
		)
		(property "Value" ""
			(at 0 0 90)
			(layer "F.Fab")
			(effects
				(font
					(size 1.27 1.27)
				)
			)
		)
		(duplicate_pad_numbers_are_jumpers no)
		(fp_line
			(start 0.299974 -0.150114)
			(end 0.299974 0.150114)
			(stroke
				(width 0.1)
				(type default)
			)
			(layer "F.Fab")
		)
		(fp_line
			(start -0.299974 -0.150114)
			(end 0.299974 -0.150114)
			(stroke
				(width 0.1)
				(type default)
			)
			(layer "F.Fab")
		)
		(fp_line
			(start 0.299974 0.150114)
			(end -0.299974 0.150114)
			(stroke
				(width 0.1)
				(type default)
			)
			(layer "F.Fab")
		)
		(fp_line
			(start -0.299974 0.150114)
			(end -0.299974 -0.150114)
			(stroke
				(width 0.1)
				(type default)
			)
			(layer "F.Fab")
		)
		(pad "1" smd rect
			(at -0.2667 0 90)
			(size 0.3048 0.381)
			(layers "F.Cu" "F.Mask" "F.Paste")
			(net "P5E_PEX0_STN7_TX_DN<124>")
		)
		(pad "2" smd rect
			(at 0.2667 0 90)
			(size 0.3048 0.381)
			(layers "F.Cu" "F.Mask" "F.Paste")
			(net "P5E_PEX0_STN7_TX_C_DN<124>")
		)
	)
	(footprint ""
		(layer "F.Cu")
		(at 491.53953 -547.603172 180)
		(property "Reference" "J39_OTH"
			(at -3.2385 -1.402334 0)
			(unlocked yes)
			(layer "B.SilkS")
			(effects
				(font
					(size 0.7874 0.5842)
					(thickness 0.1524)
				)
				(justify mirror)
			)
		)
		(property "Value" ""
			(at 0 0 180)
			(layer "F.Fab")
			(effects
				(font
					(size 1.27 1.27)
				)
			)
		)
		(duplicate_pad_numbers_are_jumpers no)
		(pad "1" thru_hole circle
			(at 0 0 180)
			(size 0.4572 0.4572)
			(drill 0.2032)
			(layers "*.Cu" "*.Mask")
			(remove_unused_layers no)
			(net "Net_9097")
			(clearance 0.127)
			(thermal_gap 0.127)
			(padstack
				(mode front_inner_back)
				(layer "Inner"
					(shape circle)
					(size 0.4572 0.4572)
					(clearance 0.127)
				)
				(layer "B.Cu"
					(shape circle)
					(size 0.508 0.508)
					(clearance 0.1016)
				)
			)
		)
	)
)
